# T6G (Grand Teton) — schematic netlist excerpt (pin names and nets, part order shuffled) for the footprints in the layout excerpt that follows; sources: Cadence DE-HDL packaged netlist, KiCad conversion of 04192023_DAF0TMB3IC0_F0TG_MB_C_brd_V02_OCP.brd

R8033  Q_RES  1K 1% CHIP  pkg 0402LF  page 83 : A = FM_ESPI_CPU0_ALERT_R_SEL ; B = GND
R534  Q_RES  2.2K 5% CHIP  pkg 0402LF  page 54 : A = CPU1_BP3 ; B = PVDD18_S5_P1

(kicad_pcb
	(version 20260206)
	(generator "pcbnew")
	(generator_version "10.0")
	(general
		(thickness 1.6)
		(legacy_teardrops no)
	)
	(paper "A4")
	(title_block
		(title "04192023_DAF0TMB3IC0_F0TG_MB_C_brd_V02_OCP.brd")
		(comment 1 "Grand Teton / footprints 5257-5258 of 8354")
	)
	(layers
		(0 "F.Cu" signal "TOP")
		(4 "In1.Cu" signal "GND")
		(6 "In2.Cu" signal "IN1")
		(8 "In3.Cu" signal "GND1")
		(10 "In4.Cu" signal "IN2")
		(12 "In5.Cu" signal "GND2")
		(14 "In6.Cu" signal "IN3")
		(16 "In7.Cu" signal "GND3")
		(18 "In8.Cu" signal "VCC")
		(20 "In9.Cu" signal "VCC1")
		(22 "In10.Cu" signal "GND4")
		(24 "In11.Cu" signal "IN4")
		(26 "In12.Cu" signal "GND5")
		(28 "In13.Cu" signal "IN5")
		(30 "In14.Cu" signal "GND6")
		(32 "In15.Cu" signal "IN6")
		(34 "In16.Cu" signal "GND7")
		(2 "B.Cu" signal "BOTTOM")
		(9 "F.Adhes" user "F.Adhesive")
		(11 "B.Adhes" user "B.Adhesive")
		(13 "F.Paste" user "Package Geometry/Pastemask Top")
		(15 "B.Paste" user "Package Geometry/Pastemask Bottom")
		(5 "F.SilkS" user "Ref Des/Silkscreen Top")
		(7 "B.SilkS" user "Ref Des/Silkscreen Bottom")
		(1 "F.Mask" user "Board Geometry/Soldermask Top")
		(3 "B.Mask" user "Board Geometry/Soldermask Bottom")
		(17 "Dwgs.User" user "User.Drawings")
		(19 "Cmts.User" user "User.Comments")
		(21 "Eco1.User" user "User.Eco1")
		(23 "Eco2.User" user "User.Eco2")
		(25 "Edge.Cuts" user "Board Geometry/Outline")
		(27 "Margin" user)
		(31 "F.CrtYd" user "Package Geometry/Place Bound Top")
		(29 "B.CrtYd" user "Package Geometry/Place Bound Bottom")
		(35 "F.Fab" user "Ref Des/Assembly Top")
		(33 "B.Fab" user "Ref Des/Assembly Bottom")
	)
	(footprint ""
		(layer "B.Cu")
		(at 93.170502 -205.14945 90)
		(property "Reference" "R534"
			(at 0 0 90)
			(layer "B.SilkS")
			(hide yes)
			(effects
				(font
					(size 1.27 1.27)
				)
				(justify mirror)
			)
		)
		(property "Value" ""
			(at 0 0 90)
			(layer "B.Fab")
			(effects
				(font
					(size 1.27 1.27)
				)
				(justify mirror)
			)
		)
		(duplicate_pad_numbers_are_jumpers no)
		(fp_line
			(start 0.7874 -0.4064)
			(end -0.7874 -0.4064)
			(stroke
				(width 0.1524)
				(type default)
			)
			(layer "B.SilkS")
		)
		(fp_line
			(start -0.7874 -0.4064)
			(end -0.7874 0.4064)
			(stroke
				(width 0.1524)
				(type default)
			)
			(layer "B.SilkS")
		)
		(fp_line
			(start 0.7874 0.4064)
			(end 0.7874 -0.4064)
			(stroke
				(width 0.1524)
				(type default)
			)
			(layer "B.SilkS")
		)
		(fp_line
			(start -0.7874 0.4064)
			(end 0.7874 0.4064)
			(stroke
				(width 0.1524)
				(type default)
			)
			(layer "B.SilkS")
		)
		(fp_line
			(start 0.67945 -0.305054)
			(end 0.12065 -0.305054)
			(stroke
				(width 0.1)
				(type default)
			)
			(layer "B.Fab")
		)
		(fp_line
			(start 0.12065 -0.305054)
			(end 0.12065 -0.2794)
			(stroke
				(width 0.1)
				(type default)
			)
			(layer "B.Fab")
		)
		(fp_line
			(start -0.12065 -0.3048)
			(end -0.67945 -0.3048)
			(stroke
				(width 0.1)
				(type default)
			)
			(layer "B.Fab")
		)
		(fp_line
			(start -0.67945 -0.3048)
			(end -0.67945 0.3048)
			(stroke
				(width 0.1)
				(type default)
			)
			(layer "B.Fab")
		)
		(fp_line
			(start 0.12065 -0.2794)
			(end -0.12065 -0.2794)
			(stroke
				(width 0.1)
				(type default)
			)
			(layer "B.Fab")
		)
		(fp_line
			(start -0.12065 -0.2794)
			(end -0.12065 -0.3048)
			(stroke
				(width 0.1)
				(type default)
			)
			(layer "B.Fab")
		)
		(fp_line
			(start 0.12065 0.2794)
			(end 0.12065 0.3048)
			(stroke
				(width 0.1)
				(type default)
			)
			(layer "B.Fab")
		)
		(fp_line
			(start -0.120396 0.2794)
			(end 0.12065 0.2794)
			(stroke
				(width 0.1)
				(type default)
			)
			(layer "B.Fab")
		)
		(fp_line
			(start 0.67945 0.3048)
			(end 0.67945 -0.305054)
			(stroke
				(width 0.1)
				(type default)
			)
			(layer "B.Fab")
		)
		(fp_line
			(start 0.12065 0.3048)
			(end 0.67945 0.3048)
			(stroke
				(width 0.1)
				(type default)
			)
			(layer "B.Fab")
		)
		(fp_line
			(start -0.120396 0.3048)
			(end -0.120396 0.2794)
			(stroke
				(width 0.1)
				(type default)
			)
			(layer "B.Fab")
		)
		(fp_line
			(start -0.67945 0.3048)
			(end -0.120396 0.3048)
			(stroke
				(width 0.1)
				(type default)
			)
			(layer "B.Fab")
		)
		(pad "1" smd circle
			(at 0.40005 0 270)
			(size 0 0)
			(layers "B.Cu" "B.Mask" "B.Paste")
			(net "CPU1_BP3")
		)
		(pad "2" smd circle
			(at -0.40005 0 270)
			(size 0 0)
			(layers "B.Cu" "B.Mask" "B.Paste")
			(net "PVDD18_S5_P1")
		)
	)
	(footprint ""
		(layer "B.Cu")
		(at 188.087 -143.256 180)
		(property "Reference" "R8033"
			(at 0 0 0)
			(layer "B.SilkS")
			(hide yes)
			(effects
				(font
					(size 1.27 1.27)
				)
				(justify mirror)
			)
		)
		(property "Value" ""
			(at 0 0 0)
			(layer "B.Fab")
			(effects
				(font
					(size 1.27 1.27)
				)
				(justify mirror)
			)
		)
		(duplicate_pad_numbers_are_jumpers no)
		(fp_line
			(start 0.7874 0.4064)
			(end 0.7874 -0.4064)
			(stroke
				(width 0.1524)
				(type default)
			)
			(layer "B.SilkS")
		)
		(fp_line
			(start 0.7874 -0.4064)
			(end -0.7874 -0.4064)
			(stroke
				(width 0.1524)
				(type default)
			)
			(layer "B.SilkS")
		)
		(fp_line
			(start -0.7874 0.4064)
			(end 0.7874 0.4064)
			(stroke
				(width 0.1524)
				(type default)
			)
			(layer "B.SilkS")
		)
		(fp_line
			(start -0.7874 -0.4064)
			(end -0.7874 0.4064)
			(stroke
				(width 0.1524)
				(type default)
			)
			(layer "B.SilkS")
		)
		(fp_line
			(start 0.67945 0.3048)
			(end 0.67945 -0.305054)
			(stroke
				(width 0.1)
				(type default)
			)
			(layer "B.Fab")
		)
		(fp_line
			(start 0.67945 -0.305054)
			(end 0.12065 -0.305054)
			(stroke
				(width 0.1)
				(type default)
			)
			(layer "B.Fab")
		)
		(fp_line
			(start 0.12065 0.3048)
			(end 0.67945 0.3048)
			(stroke
				(width 0.1)
				(type default)
			)
			(layer "B.Fab")
		)
		(fp_line
			(start 0.12065 0.2794)
			(end 0.12065 0.3048)
			(stroke
				(width 0.1)
				(type default)
			)
			(layer "B.Fab")
		)
		(fp_line
			(start 0.12065 -0.2794)
			(end -0.12065 -0.2794)
			(stroke
				(width 0.1)
				(type default)
			)
			(layer "B.Fab")
		)
		(fp_line
			(start 0.12065 -0.305054)
			(end 0.12065 -0.2794)
			(stroke
				(width 0.1)
				(type default)
			)
			(layer "B.Fab")
		)
		(fp_line
			(start -0.120396 0.3048)
			(end -0.120396 0.2794)
			(stroke
				(width 0.1)
				(type default)
			)
			(layer "B.Fab")
		)
		(fp_line
			(start -0.120396 0.2794)
			(end 0.12065 0.2794)
			(stroke
				(width 0.1)
				(type default)
			)
			(layer "B.Fab")
		)
		(fp_line
			(start -0.12065 -0.2794)
			(end -0.12065 -0.3048)
			(stroke
				(width 0.1)
				(type default)
			)
			(layer "B.Fab")
		)
		(fp_line
			(start -0.12065 -0.3048)
			(end -0.67945 -0.3048)
			(stroke
				(width 0.1)
				(type default)
			)
			(layer "B.Fab")
		)
		(fp_line
			(start -0.67945 0.3048)
			(end -0.120396 0.3048)
			(stroke
				(width 0.1)
				(type default)
			)
			(layer "B.Fab")
		)
		(fp_line
			(start -0.67945 -0.3048)
			(end -0.67945 0.3048)
			(stroke
				(width 0.1)
				(type default)
			)
			(layer "B.Fab")
		)
		(pad "1" smd circle
			(at 0.40005 0)
			(size 0 0)
			(layers "B.Cu" "B.Mask" "B.Paste")
			(net "FM_ESPI_CPU0_ALERT_R_SEL")
		)
		(pad "2" smd circle
			(at -0.40005 0)
			(size 0 0)
			(layers "B.Cu" "B.Mask" "B.Paste")
			(net "GND")
		)
	)
)
